# T6G (Grand Teton) — schematic netlist excerpt (pin names and nets, part order shuffled) for the footprints in the layout excerpt that follows; sources: Cadence DE-HDL packaged netlist, KiCad conversion of 04192023_DAF0TMB3IC0_F0TG_MB_C_brd_V02_OCP.brd

C2073  Q_CAP_DIFFBUS  DIFF BUS_0.22UF 6.3V 20% X6S  pkg C0201  page 53 : \1\ = P3E_CPU1_P5_TX_C_DP<1> ; \2\ = P3E_CPU1_P5_TX_DP<1>
C2107  Q_CAP  22UF 4V 20% X6S  pkg C0402  page 74 : A = PVDDIO_P1 ; B = GND
R6133  Q_RES  1K 1% EMPTY  pkg 0402LF  page 84 : A = FAB_REV_ID2 ; B = GND

(kicad_pcb
	(version 20260206)
	(generator "pcbnew")
	(generator_version "10.0")
	(general
		(thickness 1.6)
		(legacy_teardrops no)
	)
	(paper "A4")
	(title_block
		(title "04192023_DAF0TMB3IC0_F0TG_MB_C_brd_V02_OCP.brd")
		(comment 1 "Grand Teton / footprints 5485-5487 of 8354")
	)
	(layers
		(0 "F.Cu" signal "TOP")
		(4 "In1.Cu" signal "GND")
		(6 "In2.Cu" signal "IN1")
		(8 "In3.Cu" signal "GND1")
		(10 "In4.Cu" signal "IN2")
		(12 "In5.Cu" signal "GND2")
		(14 "In6.Cu" signal "IN3")
		(16 "In7.Cu" signal "GND3")
		(18 "In8.Cu" signal "VCC")
		(20 "In9.Cu" signal "VCC1")
		(22 "In10.Cu" signal "GND4")
		(24 "In11.Cu" signal "IN4")
		(26 "In12.Cu" signal "GND5")
		(28 "In13.Cu" signal "IN5")
		(30 "In14.Cu" signal "GND6")
		(32 "In15.Cu" signal "IN6")
		(34 "In16.Cu" signal "GND7")
		(2 "B.Cu" signal "BOTTOM")
		(9 "F.Adhes" user "F.Adhesive")
		(11 "B.Adhes" user "B.Adhesive")
		(13 "F.Paste" user "Package Geometry/Pastemask Top")
		(15 "B.Paste" user "Package Geometry/Pastemask Bottom")
		(5 "F.SilkS" user "Ref Des/Silkscreen Top")
		(7 "B.SilkS" user "Ref Des/Silkscreen Bottom")
		(1 "F.Mask" user "Board Geometry/Soldermask Top")
		(3 "B.Mask" user "Board Geometry/Soldermask Bottom")
		(17 "Dwgs.User" user "User.Drawings")
		(19 "Cmts.User" user "User.Comments")
		(21 "Eco1.User" user "User.Eco1")
		(23 "Eco2.User" user "User.Eco2")
		(25 "Edge.Cuts" user "Board Geometry/Outline")
		(27 "Margin" user)
		(31 "F.CrtYd" user "Package Geometry/Place Bound Top")
		(29 "B.CrtYd" user "Package Geometry/Place Bound Bottom")
		(35 "F.Fab" user "Ref Des/Assembly Top")
		(33 "B.Fab" user "Ref Des/Assembly Bottom")
	)
	(footprint ""
		(layer "B.Cu")
		(at 44.14901 -413.691578)
		(property "Reference" "C2073"
			(at 0 0 0)
			(layer "B.SilkS")
			(hide yes)
			(effects
				(font
					(size 1.27 1.27)
				)
				(justify mirror)
			)
		)
		(property "Value" ""
			(at 0 0 0)
			(layer "B.Fab")
			(effects
				(font
					(size 1.27 1.27)
				)
				(justify mirror)
			)
		)
		(duplicate_pad_numbers_are_jumpers no)
		(fp_line
			(start -0.299974 -0.150114)
			(end -0.299974 0.150114)
			(stroke
				(width 0.1)
				(type default)
			)
			(layer "B.Fab")
		)
		(fp_line
			(start -0.299974 0.150114)
			(end 0.299974 0.150114)
			(stroke
				(width 0.1)
				(type default)
			)
			(layer "B.Fab")
		)
		(fp_line
			(start 0.299974 -0.150114)
			(end -0.299974 -0.150114)
			(stroke
				(width 0.1)
				(type default)
			)
			(layer "B.Fab")
		)
		(fp_line
			(start 0.299974 0.150114)
			(end 0.299974 -0.150114)
			(stroke
				(width 0.1)
				(type default)
			)
			(layer "B.Fab")
		)
		(pad "1" smd rect
			(at 0.2667 0 180)
			(size 0.3048 0.381)
			(layers "B.Cu" "B.Mask" "B.Paste")
			(net "P3E_CPU1_P5_TX_C_DP<1>")
		)
		(pad "2" smd rect
			(at -0.2667 0 180)
			(size 0.3048 0.381)
			(layers "B.Cu" "B.Mask" "B.Paste")
			(net "P3E_CPU1_P5_TX_DP<1>")
		)
	)
	(footprint ""
		(layer "B.Cu")
		(at 393.809728 -200.742804 90)
		(property "Reference" "R6133"
			(at 0 0 90)
			(layer "B.SilkS")
			(hide yes)
			(effects
				(font
					(size 1.27 1.27)
				)
				(justify mirror)
			)
		)
		(property "Value" ""
			(at 0 0 90)
			(layer "B.Fab")
			(effects
				(font
					(size 1.27 1.27)
				)
				(justify mirror)
			)
		)
		(duplicate_pad_numbers_are_jumpers no)
		(fp_line
			(start 0.7874 -0.4064)
			(end -0.7874 -0.4064)
			(stroke
				(width 0.1524)
				(type default)
			)
			(layer "B.SilkS")
		)
		(fp_line
			(start -0.7874 -0.4064)
			(end -0.7874 0.4064)
			(stroke
				(width 0.1524)
				(type default)
			)
			(layer "B.SilkS")
		)
		(fp_line
			(start 0.7874 0.4064)
			(end 0.7874 -0.4064)
			(stroke
				(width 0.1524)
				(type default)
			)
			(layer "B.SilkS")
		)
		(fp_line
			(start -0.7874 0.4064)
			(end 0.7874 0.4064)
			(stroke
				(width 0.1524)
				(type default)
			)
			(layer "B.SilkS")
		)
		(fp_line
			(start 0.67945 -0.305054)
			(end 0.12065 -0.305054)
			(stroke
				(width 0.1)
				(type default)
			)
			(layer "B.Fab")
		)
		(fp_line
			(start 0.12065 -0.305054)
			(end 0.12065 -0.2794)
			(stroke
				(width 0.1)
				(type default)
			)
			(layer "B.Fab")
		)
		(fp_line
			(start -0.12065 -0.3048)
			(end -0.67945 -0.3048)
			(stroke
				(width 0.1)
				(type default)
			)
			(layer "B.Fab")
		)
		(fp_line
			(start -0.67945 -0.3048)
			(end -0.67945 0.3048)
			(stroke
				(width 0.1)
				(type default)
			)
			(layer "B.Fab")
		)
		(fp_line
			(start 0.12065 -0.2794)
			(end -0.12065 -0.2794)
			(stroke
				(width 0.1)
				(type default)
			)
			(layer "B.Fab")
		)
		(fp_line
			(start -0.12065 -0.2794)
			(end -0.12065 -0.3048)
			(stroke
				(width 0.1)
				(type default)
			)
			(layer "B.Fab")
		)
		(fp_line
			(start 0.12065 0.2794)
			(end 0.12065 0.3048)
			(stroke
				(width 0.1)
				(type default)
			)
			(layer "B.Fab")
		)
		(fp_line
			(start -0.120396 0.2794)
			(end 0.12065 0.2794)
			(stroke
				(width 0.1)
				(type default)
			)
			(layer "B.Fab")
		)
		(fp_line
			(start 0.67945 0.3048)
			(end 0.67945 -0.305054)
			(stroke
				(width 0.1)
				(type default)
			)
			(layer "B.Fab")
		)
		(fp_line
			(start 0.12065 0.3048)
			(end 0.67945 0.3048)
			(stroke
				(width 0.1)
				(type default)
			)
			(layer "B.Fab")
		)
		(fp_line
			(start -0.120396 0.3048)
			(end -0.120396 0.2794)
			(stroke
				(width 0.1)
				(type default)
			)
			(layer "B.Fab")
		)
		(fp_line
			(start -0.67945 0.3048)
			(end -0.120396 0.3048)
			(stroke
				(width 0.1)
				(type default)
			)
			(layer "B.Fab")
		)
		(pad "1" smd circle
			(at 0.40005 0 270)
			(size 0 0)
			(layers "B.Cu" "B.Mask" "B.Paste")
			(net "FAB_REV_ID2")
		)
		(pad "2" smd circle
			(at -0.40005 0 270)
			(size 0 0)
			(layers "B.Cu" "B.Mask" "B.Paste")
			(net "GND")
		)
	)
	(footprint ""
		(layer "B.Cu")
		(at 98.578924 -259.73024 180)
		(property "Reference" "C2107"
			(at 0 0 0)
			(layer "B.SilkS")
			(hide yes)
			(effects
				(font
					(size 1.27 1.27)
				)
				(justify mirror)
			)
		)
		(property "Value" ""
			(at 0 0 0)
			(layer "B.Fab")
			(effects
				(font
					(size 1.27 1.27)
				)
				(justify mirror)
			)
		)
		(duplicate_pad_numbers_are_jumpers no)
		(fp_line
			(start 0.7874 0.4064)
			(end 0.7874 -0.4064)
			(stroke
				(width 0.1524)
				(type default)
			)
			(layer "B.SilkS")
		)
		(fp_line
			(start 0.7874 -0.4064)
			(end -0.7874 -0.4064)
			(stroke
				(width 0.1524)
				(type default)
			)
			(layer "B.SilkS")
		)
		(fp_line
			(start -0.7874 0.4064)
			(end 0.7874 0.4064)
			(stroke
				(width 0.1524)
				(type default)
			)
			(layer "B.SilkS")
		)
		(fp_line
			(start -0.7874 -0.4064)
			(end -0.7874 0.4064)
			(stroke
				(width 0.1524)
				(type default)
			)
			(layer "B.SilkS")
		)
		(fp_line
			(start 0.67945 0.3048)
			(end 0.67945 -0.305054)
			(stroke
				(width 0.1)
				(type default)
			)
			(layer "B.Fab")
		)
		(fp_line
			(start 0.67945 -0.305054)
			(end 0.12065 -0.305054)
			(stroke
				(width 0.1)
				(type default)
			)
			(layer "B.Fab")
		)
		(fp_line
			(start 0.12065 0.3048)
			(end 0.67945 0.3048)
			(stroke
				(width 0.1)
				(type default)
			)
			(layer "B.Fab")
		)
		(fp_line
			(start 0.12065 0.2794)
			(end 0.12065 0.3048)
			(stroke
				(width 0.1)
				(type default)
			)
			(layer "B.Fab")
		)
		(fp_line
			(start 0.12065 -0.2794)
			(end -0.12065 -0.2794)
			(stroke
				(width 0.1)
				(type default)
			)
			(layer "B.Fab")
		)
		(fp_line
			(start 0.12065 -0.305054)
			(end 0.12065 -0.2794)
			(stroke
				(width 0.1)
				(type default)
			)
			(layer "B.Fab")
		)
		(fp_line
			(start -0.120396 0.3048)
			(end -0.120396 0.2794)
			(stroke
				(width 0.1)
				(type default)
			)
			(layer "B.Fab")
		)
		(fp_line
			(start -0.120396 0.2794)
			(end 0.12065 0.2794)
			(stroke
				(width 0.1)
				(type default)
			)
			(layer "B.Fab")
		)
		(fp_line
			(start -0.12065 -0.2794)
			(end -0.12065 -0.3048)
			(stroke
				(width 0.1)
				(type default)
			)
			(layer "B.Fab")
		)
		(fp_line
			(start -0.12065 -0.3048)
			(end -0.67945 -0.3048)
			(stroke
				(width 0.1)
				(type default)
			)
			(layer "B.Fab")
		)
		(fp_line
			(start -0.67945 0.3048)
			(end -0.120396 0.3048)
			(stroke
				(width 0.1)
				(type default)
			)
			(layer "B.Fab")
		)
		(fp_line
			(start -0.67945 -0.3048)
			(end -0.67945 0.3048)
			(stroke
				(width 0.1)
				(type default)
			)
			(layer "B.Fab")
		)
		(pad "1" smd circle
			(at 0.40005 0)
			(size 0 0)
			(layers "B.Cu" "B.Mask" "B.Paste")
			(net "PVDDIO_P1")
		)
		(pad "2" smd circle
			(at -0.40005 0)
			(size 0 0)
			(layers "B.Cu" "B.Mask" "B.Paste")
			(net "GND")
		)
	)
)
